# T6G (Grand Teton) — schematic netlist excerpt (pin names and nets, part order shuffled) for the footprints in the layout excerpt that follows; sources: Cadence DE-HDL packaged netlist, KiCad conversion of 04192023_DAF0TMB3IC0_F0TG_MB_C_brd_V02_OCP.brd

C759  Q_CAP_DIFFBUS  DIFF BUS_0.22UF 6.3V 20% X6S  pkg C0201  page 66 : \1\ = P5E_CPU1_P2_TX_C_DP<7> ; \2\ = P5E_CPU1_P2_TX_DP<7>
R6181  Q_RES  4.7K 5% CHIP  pkg 0402LF  page 171 : A = P3V3_AUX ; B = PU_U212_EN_N
PL8066  Q_INDUCTOR  1.5UH/53A IND  pkg SMLF  page 190 : \1\ = SW_P3V3_AUX_SW ; \2\ = P3V3_AUX

(kicad_pcb
	(version 20260206)
	(generator "pcbnew")
	(generator_version "10.0")
	(general
		(thickness 1.6)
		(legacy_teardrops no)
	)
	(paper "A4")
	(title_block
		(title "04192023_DAF0TMB3IC0_F0TG_MB_C_brd_V02_OCP.brd")
		(comment 1 "Grand Teton / footprints 4464-4466 of 8354")
	)
	(layers
		(0 "F.Cu" signal "TOP")
		(4 "In1.Cu" signal "GND")
		(6 "In2.Cu" signal "IN1")
		(8 "In3.Cu" signal "GND1")
		(10 "In4.Cu" signal "IN2")
		(12 "In5.Cu" signal "GND2")
		(14 "In6.Cu" signal "IN3")
		(16 "In7.Cu" signal "GND3")
		(18 "In8.Cu" signal "VCC")
		(20 "In9.Cu" signal "VCC1")
		(22 "In10.Cu" signal "GND4")
		(24 "In11.Cu" signal "IN4")
		(26 "In12.Cu" signal "GND5")
		(28 "In13.Cu" signal "IN5")
		(30 "In14.Cu" signal "GND6")
		(32 "In15.Cu" signal "IN6")
		(34 "In16.Cu" signal "GND7")
		(2 "B.Cu" signal "BOTTOM")
		(9 "F.Adhes" user "F.Adhesive")
		(11 "B.Adhes" user "B.Adhesive")
		(13 "F.Paste" user "Package Geometry/Pastemask Top")
		(15 "B.Paste" user "Package Geometry/Pastemask Bottom")
		(5 "F.SilkS" user "Ref Des/Silkscreen Top")
		(7 "B.SilkS" user "Ref Des/Silkscreen Bottom")
		(1 "F.Mask" user "Board Geometry/Soldermask Top")
		(3 "B.Mask" user "Board Geometry/Soldermask Bottom")
		(17 "Dwgs.User" user "User.Drawings")
		(19 "Cmts.User" user "User.Comments")
		(21 "Eco1.User" user "User.Eco1")
		(23 "Eco2.User" user "User.Eco2")
		(25 "Edge.Cuts" user "Board Geometry/Outline")
		(27 "Margin" user)
		(31 "F.CrtYd" user "Package Geometry/Place Bound Top")
		(29 "B.CrtYd" user "Package Geometry/Place Bound Bottom")
		(35 "F.Fab" user "Ref Des/Assembly Top")
		(33 "B.Fab" user "Ref Des/Assembly Bottom")
	)
	(footprint ""
		(layer "F.Cu")
		(at 456.132184 -62.074298 90)
		(property "Reference" "PL8066"
			(at -4.96824 -7.257288 90)
			(unlocked yes)
			(layer "F.SilkS")
			(effects
				(font
					(size 0.7874 0.5842)
					(thickness 0.1524)
				)
				(justify left)
			)
		)
		(property "Value" ""
			(at 0 0 90)
			(layer "F.Fab")
			(effects
				(font
					(size 1.27 1.27)
				)
			)
		)
		(duplicate_pad_numbers_are_jumpers no)
		(fp_line
			(start 7.1501 -6.450076)
			(end -7.1501 -6.450076)
			(stroke
				(width 0.1524)
				(type default)
			)
			(layer "F.SilkS")
		)
		(fp_line
			(start -7.1501 -6.450076)
			(end -7.1501 -2.6416)
			(stroke
				(width 0.1524)
				(type default)
			)
			(layer "F.SilkS")
		)
		(fp_line
			(start 7.1501 -2.6416)
			(end 7.1501 -6.450076)
			(stroke
				(width 0.1524)
				(type default)
			)
			(layer "F.SilkS")
		)
		(fp_line
			(start 7.1501 2.6416)
			(end 7.1501 6.450076)
			(stroke
				(width 0.1524)
				(type default)
			)
			(layer "F.SilkS")
		)
		(fp_line
			(start 7.1501 6.450076)
			(end -7.1501 6.450076)
			(stroke
				(width 0.1524)
				(type default)
			)
			(layer "F.SilkS")
		)
		(fp_line
			(start -7.1501 6.450076)
			(end -7.1501 2.6416)
			(stroke
				(width 0.1524)
				(type default)
			)
			(layer "F.SilkS")
		)
		(fp_line
			(start 7.1501 -6.450076)
			(end -7.1501 -6.450076)
			(stroke
				(width 0.1)
				(type default)
			)
			(layer "F.Fab")
		)
		(fp_line
			(start -7.1501 -6.450076)
			(end -7.1501 6.450076)
			(stroke
				(width 0.1)
				(type default)
			)
			(layer "F.Fab")
		)
		(fp_line
			(start 7.1501 6.450076)
			(end 7.1501 -6.450076)
			(stroke
				(width 0.1)
				(type default)
			)
			(layer "F.Fab")
		)
		(fp_line
			(start -7.1501 6.450076)
			(end 7.1501 6.450076)
			(stroke
				(width 0.1)
				(type default)
			)
			(layer "F.Fab")
		)
		(pad "1" smd rect
			(at -5.625084 0 90)
			(size 3.2512 5.0038)
			(layers "F.Cu" "F.Mask" "F.Paste")
			(net "SW_P3V3_AUX_SW")
		)
		(pad "2" smd rect
			(at 5.625084 0 90)
			(size 3.2512 5.0038)
			(layers "F.Cu" "F.Mask" "F.Paste")
			(net "P3V3_AUX")
		)
	)
	(footprint ""
		(layer "F.Cu")
		(at 154.530044 -375.49963 -90)
		(property "Reference" "C759"
			(at 0 0 270)
			(layer "F.SilkS")
			(hide yes)
			(effects
				(font
					(size 1.27 1.27)
				)
			)
		)
		(property "Value" ""
			(at 0 0 270)
			(layer "F.Fab")
			(effects
				(font
					(size 1.27 1.27)
				)
			)
		)
		(duplicate_pad_numbers_are_jumpers no)
		(fp_line
			(start -0.299974 0.150114)
			(end -0.299974 -0.150114)
			(stroke
				(width 0.1)
				(type default)
			)
			(layer "F.Fab")
		)
		(fp_line
			(start 0.299974 0.150114)
			(end -0.299974 0.150114)
			(stroke
				(width 0.1)
				(type default)
			)
			(layer "F.Fab")
		)
		(fp_line
			(start -0.299974 -0.150114)
			(end 0.299974 -0.150114)
			(stroke
				(width 0.1)
				(type default)
			)
			(layer "F.Fab")
		)
		(fp_line
			(start 0.299974 -0.150114)
			(end 0.299974 0.150114)
			(stroke
				(width 0.1)
				(type default)
			)
			(layer "F.Fab")
		)
		(pad "1" smd rect
			(at -0.2667 0 270)
			(size 0.3048 0.381)
			(layers "F.Cu" "F.Mask" "F.Paste")
			(net "P5E_CPU1_P2_TX_C_DP<7>")
		)
		(pad "2" smd rect
			(at 0.2667 0 270)
			(size 0.3048 0.381)
			(layers "F.Cu" "F.Mask" "F.Paste")
			(net "P5E_CPU1_P2_TX_DP<7>")
		)
	)
	(footprint ""
		(layer "F.Cu")
		(at 29.214064 -75.234038 -90)
		(property "Reference" "R6181"
			(at 0 0 270)
			(layer "F.SilkS")
			(hide yes)
			(effects
				(font
					(size 1.27 1.27)
				)
			)
		)
		(property "Value" ""
			(at 0 0 270)
			(layer "F.Fab")
			(effects
				(font
					(size 1.27 1.27)
				)
			)
		)
		(duplicate_pad_numbers_are_jumpers no)
		(fp_line
			(start -0.7874 0.4064)
			(end -0.7874 -0.4064)
			(stroke
				(width 0.1524)
				(type default)
			)
			(layer "F.SilkS")
		)
		(fp_line
			(start 0.7874 0.4064)
			(end -0.7874 0.4064)
			(stroke
				(width 0.1524)
				(type default)
			)
			(layer "F.SilkS")
		)
		(fp_line
			(start -0.7874 -0.4064)
			(end 0.7874 -0.4064)
			(stroke
				(width 0.1524)
				(type default)
			)
			(layer "F.SilkS")
		)
		(fp_line
			(start 0.7874 -0.4064)
			(end 0.7874 0.4064)
			(stroke
				(width 0.1524)
				(type default)
			)
			(layer "F.SilkS")
		)
		(fp_line
			(start -0.67945 0.3048)
			(end -0.67945 -0.305054)
			(stroke
				(width 0.1)
				(type default)
			)
			(layer "F.Fab")
		)
		(fp_line
			(start -0.12065 0.3048)
			(end -0.67945 0.3048)
			(stroke
				(width 0.1)
				(type default)
			)
			(layer "F.Fab")
		)
		(fp_line
			(start 0.120396 0.3048)
			(end 0.120396 0.2794)
			(stroke
				(width 0.1)
				(type default)
			)
			(layer "F.Fab")
		)
		(fp_line
			(start 0.67945 0.3048)
			(end 0.120396 0.3048)
			(stroke
				(width 0.1)
				(type default)
			)
			(layer "F.Fab")
		)
		(fp_line
			(start -0.12065 0.2794)
			(end -0.12065 0.3048)
			(stroke
				(width 0.1)
				(type default)
			)
			(layer "F.Fab")
		)
		(fp_line
			(start 0.120396 0.2794)
			(end -0.12065 0.2794)
			(stroke
				(width 0.1)
				(type default)
			)
			(layer "F.Fab")
		)
		(fp_line
			(start -0.12065 -0.2794)
			(end 0.12065 -0.2794)
			(stroke
				(width 0.1)
				(type default)
			)
			(layer "F.Fab")
		)
		(fp_line
			(start 0.12065 -0.2794)
			(end 0.12065 -0.3048)
			(stroke
				(width 0.1)
				(type default)
			)
			(layer "F.Fab")
		)
		(fp_line
			(start 0.12065 -0.3048)
			(end 0.67945 -0.3048)
			(stroke
				(width 0.1)
				(type default)
			)
			(layer "F.Fab")
		)
		(fp_line
			(start 0.67945 -0.3048)
			(end 0.67945 0.3048)
			(stroke
				(width 0.1)
				(type default)
			)
			(layer "F.Fab")
		)
		(fp_line
			(start -0.67945 -0.305054)
			(end -0.12065 -0.305054)
			(stroke
				(width 0.1)
				(type default)
			)
			(layer "F.Fab")
		)
		(fp_line
			(start -0.12065 -0.305054)
			(end -0.12065 -0.2794)
			(stroke
				(width 0.1)
				(type default)
			)
			(layer "F.Fab")
		)
		(pad "1" smd circle
			(at -0.40005 0 270)
			(size 0 0)
			(layers "F.Cu" "F.Mask" "F.Paste")
			(net "P3V3_AUX")
		)
		(pad "2" smd circle
			(at 0.40005 0 270)
			(size 0 0)
			(layers "F.Cu" "F.Mask" "F.Paste")
			(net "PU_U212_EN_N")
		)
	)
)
